# T6G (Grand Teton) — schematic netlist excerpt (pin names and nets, part order shuffled) for the footprints in the layout excerpt that follows; sources: Cadence DE-HDL packaged netlist, KiCad conversion of 04192023_DAF0TMB3IC0_F0TG_MB_C_brd_V02_OCP.brd

R257  Q_RES  0 5% EMPTY  pkg 0402LF  page 160 : A = SMB_CPU0_CPU1_APML_BUF1_SDA_R2 ; B = SMB_CPU0_CPU1_APML_SDA_R2
C6533  Q_CAP_DIFFBUS  DIFF BUS_0.22UF 6.3V 20% X6S  pkg C0201  page 286 : \1\ = P5E_CPU0_P1_TX_BUF_C_DP<0> ; \2\ = P5E_CPU0_P1_TX_BUF_DP<0>
C2228  Q_CAP  22UF 4V 20% X6S  pkg C0402  page 69 : A = PVDDCR_CPU1_P0 ; B = GND

(kicad_pcb
	(version 20260206)
	(generator "pcbnew")
	(generator_version "10.0")
	(general
		(thickness 1.6)
		(legacy_teardrops no)
	)
	(paper "A4")
	(title_block
		(title "04192023_DAF0TMB3IC0_F0TG_MB_C_brd_V02_OCP.brd")
		(comment 1 "Grand Teton / footprints 5812-5814 of 8354")
	)
	(layers
		(0 "F.Cu" signal "TOP")
		(4 "In1.Cu" signal "GND")
		(6 "In2.Cu" signal "IN1")
		(8 "In3.Cu" signal "GND1")
		(10 "In4.Cu" signal "IN2")
		(12 "In5.Cu" signal "GND2")
		(14 "In6.Cu" signal "IN3")
		(16 "In7.Cu" signal "GND3")
		(18 "In8.Cu" signal "VCC")
		(20 "In9.Cu" signal "VCC1")
		(22 "In10.Cu" signal "GND4")
		(24 "In11.Cu" signal "IN4")
		(26 "In12.Cu" signal "GND5")
		(28 "In13.Cu" signal "IN5")
		(30 "In14.Cu" signal "GND6")
		(32 "In15.Cu" signal "IN6")
		(34 "In16.Cu" signal "GND7")
		(2 "B.Cu" signal "BOTTOM")
		(9 "F.Adhes" user "F.Adhesive")
		(11 "B.Adhes" user "B.Adhesive")
		(13 "F.Paste" user "Package Geometry/Pastemask Top")
		(15 "B.Paste" user "Package Geometry/Pastemask Bottom")
		(5 "F.SilkS" user "Ref Des/Silkscreen Top")
		(7 "B.SilkS" user "Ref Des/Silkscreen Bottom")
		(1 "F.Mask" user "Board Geometry/Soldermask Top")
		(3 "B.Mask" user "Board Geometry/Soldermask Bottom")
		(17 "Dwgs.User" user "User.Drawings")
		(19 "Cmts.User" user "User.Comments")
		(21 "Eco1.User" user "User.Eco1")
		(23 "Eco2.User" user "User.Eco2")
		(25 "Edge.Cuts" user "Board Geometry/Outline")
		(27 "Margin" user)
		(31 "F.CrtYd" user "Package Geometry/Place Bound Top")
		(29 "B.CrtYd" user "Package Geometry/Place Bound Bottom")
		(35 "F.Fab" user "Ref Des/Assembly Top")
		(33 "B.Fab" user "Ref Des/Assembly Bottom")
	)
	(footprint ""
		(layer "B.Cu")
		(at 235.086398 -213.258654)
		(property "Reference" "R257"
			(at 0 0 0)
			(layer "B.SilkS")
			(hide yes)
			(effects
				(font
					(size 1.27 1.27)
				)
				(justify mirror)
			)
		)
		(property "Value" ""
			(at 0 0 0)
			(layer "B.Fab")
			(effects
				(font
					(size 1.27 1.27)
				)
				(justify mirror)
			)
		)
		(duplicate_pad_numbers_are_jumpers no)
		(fp_line
			(start -0.7874 -0.4064)
			(end -0.7874 0.4064)
			(stroke
				(width 0.1524)
				(type default)
			)
			(layer "B.SilkS")
		)
		(fp_line
			(start -0.7874 0.4064)
			(end 0.7874 0.4064)
			(stroke
				(width 0.1524)
				(type default)
			)
			(layer "B.SilkS")
		)
		(fp_line
			(start 0.7874 -0.4064)
			(end -0.7874 -0.4064)
			(stroke
				(width 0.1524)
				(type default)
			)
			(layer "B.SilkS")
		)
		(fp_line
			(start 0.7874 0.4064)
			(end 0.7874 -0.4064)
			(stroke
				(width 0.1524)
				(type default)
			)
			(layer "B.SilkS")
		)
		(fp_line
			(start -0.67945 -0.3048)
			(end -0.67945 0.3048)
			(stroke
				(width 0.1)
				(type default)
			)
			(layer "B.Fab")
		)
		(fp_line
			(start -0.67945 0.3048)
			(end -0.120396 0.3048)
			(stroke
				(width 0.1)
				(type default)
			)
			(layer "B.Fab")
		)
		(fp_line
			(start -0.12065 -0.3048)
			(end -0.67945 -0.3048)
			(stroke
				(width 0.1)
				(type default)
			)
			(layer "B.Fab")
		)
		(fp_line
			(start -0.12065 -0.2794)
			(end -0.12065 -0.3048)
			(stroke
				(width 0.1)
				(type default)
			)
			(layer "B.Fab")
		)
		(fp_line
			(start -0.120396 0.2794)
			(end 0.12065 0.2794)
			(stroke
				(width 0.1)
				(type default)
			)
			(layer "B.Fab")
		)
		(fp_line
			(start -0.120396 0.3048)
			(end -0.120396 0.2794)
			(stroke
				(width 0.1)
				(type default)
			)
			(layer "B.Fab")
		)
		(fp_line
			(start 0.12065 -0.305054)
			(end 0.12065 -0.2794)
			(stroke
				(width 0.1)
				(type default)
			)
			(layer "B.Fab")
		)
		(fp_line
			(start 0.12065 -0.2794)
			(end -0.12065 -0.2794)
			(stroke
				(width 0.1)
				(type default)
			)
			(layer "B.Fab")
		)
		(fp_line
			(start 0.12065 0.2794)
			(end 0.12065 0.3048)
			(stroke
				(width 0.1)
				(type default)
			)
			(layer "B.Fab")
		)
		(fp_line
			(start 0.12065 0.3048)
			(end 0.67945 0.3048)
			(stroke
				(width 0.1)
				(type default)
			)
			(layer "B.Fab")
		)
		(fp_line
			(start 0.67945 -0.305054)
			(end 0.12065 -0.305054)
			(stroke
				(width 0.1)
				(type default)
			)
			(layer "B.Fab")
		)
		(fp_line
			(start 0.67945 0.3048)
			(end 0.67945 -0.305054)
			(stroke
				(width 0.1)
				(type default)
			)
			(layer "B.Fab")
		)
		(pad "1" smd rect
			(at 0.40005 0)
			(size 0.4572 0.508)
			(layers "B.Cu" "B.Mask" "B.Paste")
			(net "SMB_CPU0_CPU1_APML_BUF1_SDA_R2")
		)
		(pad "2" smd rect
			(at -0.40005 0)
			(size 0.4572 0.508)
			(layers "B.Cu" "B.Mask" "B.Paste")
			(net "SMB_CPU0_CPU1_APML_SDA_R2")
		)
	)
	(footprint ""
		(layer "B.Cu")
		(at 370.427758 -269.30731)
		(property "Reference" "C2228"
			(at 0 0 0)
			(layer "B.SilkS")
			(hide yes)
			(effects
				(font
					(size 1.27 1.27)
				)
				(justify mirror)
			)
		)
		(property "Value" ""
			(at 0 0 0)
			(layer "B.Fab")
			(effects
				(font
					(size 1.27 1.27)
				)
				(justify mirror)
			)
		)
		(duplicate_pad_numbers_are_jumpers no)
		(fp_line
			(start -0.7874 -0.4064)
			(end -0.7874 0.4064)
			(stroke
				(width 0.1524)
				(type default)
			)
			(layer "B.SilkS")
		)
		(fp_line
			(start -0.7874 0.4064)
			(end 0.7874 0.4064)
			(stroke
				(width 0.1524)
				(type default)
			)
			(layer "B.SilkS")
		)
		(fp_line
			(start 0.7874 -0.4064)
			(end -0.7874 -0.4064)
			(stroke
				(width 0.1524)
				(type default)
			)
			(layer "B.SilkS")
		)
		(fp_line
			(start 0.7874 0.4064)
			(end 0.7874 -0.4064)
			(stroke
				(width 0.1524)
				(type default)
			)
			(layer "B.SilkS")
		)
		(fp_line
			(start -0.67945 -0.3048)
			(end -0.67945 0.3048)
			(stroke
				(width 0.1)
				(type default)
			)
			(layer "B.Fab")
		)
		(fp_line
			(start -0.67945 0.3048)
			(end -0.120396 0.3048)
			(stroke
				(width 0.1)
				(type default)
			)
			(layer "B.Fab")
		)
		(fp_line
			(start -0.12065 -0.3048)
			(end -0.67945 -0.3048)
			(stroke
				(width 0.1)
				(type default)
			)
			(layer "B.Fab")
		)
		(fp_line
			(start -0.12065 -0.2794)
			(end -0.12065 -0.3048)
			(stroke
				(width 0.1)
				(type default)
			)
			(layer "B.Fab")
		)
		(fp_line
			(start -0.120396 0.2794)
			(end 0.12065 0.2794)
			(stroke
				(width 0.1)
				(type default)
			)
			(layer "B.Fab")
		)
		(fp_line
			(start -0.120396 0.3048)
			(end -0.120396 0.2794)
			(stroke
				(width 0.1)
				(type default)
			)
			(layer "B.Fab")
		)
		(fp_line
			(start 0.12065 -0.305054)
			(end 0.12065 -0.2794)
			(stroke
				(width 0.1)
				(type default)
			)
			(layer "B.Fab")
		)
		(fp_line
			(start 0.12065 -0.2794)
			(end -0.12065 -0.2794)
			(stroke
				(width 0.1)
				(type default)
			)
			(layer "B.Fab")
		)
		(fp_line
			(start 0.12065 0.2794)
			(end 0.12065 0.3048)
			(stroke
				(width 0.1)
				(type default)
			)
			(layer "B.Fab")
		)
		(fp_line
			(start 0.12065 0.3048)
			(end 0.67945 0.3048)
			(stroke
				(width 0.1)
				(type default)
			)
			(layer "B.Fab")
		)
		(fp_line
			(start 0.67945 -0.305054)
			(end 0.12065 -0.305054)
			(stroke
				(width 0.1)
				(type default)
			)
			(layer "B.Fab")
		)
		(fp_line
			(start 0.67945 0.3048)
			(end 0.67945 -0.305054)
			(stroke
				(width 0.1)
				(type default)
			)
			(layer "B.Fab")
		)
		(pad "1" smd circle
			(at 0.40005 0 180)
			(size 0 0)
			(layers "B.Cu" "B.Mask" "B.Paste")
			(net "PVDDCR_CPU1_P0")
		)
		(pad "2" smd circle
			(at -0.40005 0 180)
			(size 0 0)
			(layers "B.Cu" "B.Mask" "B.Paste")
			(net "GND")
		)
	)
	(footprint ""
		(layer "B.Cu")
		(at 306.214526 -416.899344 90)
		(property "Reference" "C6533"
			(at 0 0 90)
			(layer "B.SilkS")
			(hide yes)
			(effects
				(font
					(size 1.27 1.27)
				)
				(justify mirror)
			)
		)
		(property "Value" ""
			(at 0 0 90)
			(layer "B.Fab")
			(effects
				(font
					(size 1.27 1.27)
				)
				(justify mirror)
			)
		)
		(duplicate_pad_numbers_are_jumpers no)
		(fp_line
			(start 0.299974 -0.150114)
			(end -0.299974 -0.150114)
			(stroke
				(width 0.1)
				(type default)
			)
			(layer "B.Fab")
		)
		(fp_line
			(start -0.299974 -0.150114)
			(end -0.299974 0.150114)
			(stroke
				(width 0.1)
				(type default)
			)
			(layer "B.Fab")
		)
		(fp_line
			(start 0.299974 0.150114)
			(end 0.299974 -0.150114)
			(stroke
				(width 0.1)
				(type default)
			)
			(layer "B.Fab")
		)
		(fp_line
			(start -0.299974 0.150114)
			(end 0.299974 0.150114)
			(stroke
				(width 0.1)
				(type default)
			)
			(layer "B.Fab")
		)
		(pad "1" smd rect
			(at 0.2667 0 270)
			(size 0.3048 0.381)
			(layers "B.Cu" "B.Mask" "B.Paste")
			(net "P5E_CPU0_P1_TX_BUF_C_DP<0>")
		)
		(pad "2" smd rect
			(at -0.2667 0 270)
			(size 0.3048 0.381)
			(layers "B.Cu" "B.Mask" "B.Paste")
			(net "P5E_CPU0_P1_TX_BUF_DP<0>")
		)
	)
)
